# S9S_MB_2U (Grand Teton) — schematic netlist excerpt (pin names and nets, part order shuffled) for the footprints in the layout excerpt that follows; sources: Cadence DE-HDL packaged netlist, KiCad conversion of 03242023_DA0F0TMBIJ0_F0T_Motherboard_J_brd_V01_OCP.brd

C530  Q_CAP  47UF 4V 20% X6S  pkg C0805  page 76 : A = PVCCINFAON_CPU0 ; B = GND
R3346  Q_RES  1 1% CHIP  pkg 0603LF  page 217 : A = P3V3_AUX ; B = P3V3_AUX_FPGA_VCCIO0
PC1680  Q_CAP  22UF 16V 20% X6S  pkg C0805  page 289 : A = SW_P12V_PVCCFA_EHV_FIVRA_CPU1_L ; B = GND

(kicad_pcb
	(version 20260206)
	(generator "pcbnew")
	(generator_version "10.0")
	(general
		(thickness 1.6)
		(legacy_teardrops no)
	)
	(paper "A4")
	(title_block
		(title "03242023_DA0F0TMBIJ0_F0T_Motherboard_J_brd_V01_OCP.brd")
		(comment 1 "Grand Teton / footprints 5035-5037 of 6105")
	)
	(layers
		(0 "F.Cu" signal "TOP")
		(4 "In1.Cu" signal "GND")
		(6 "In2.Cu" signal "IN1")
		(8 "In3.Cu" signal "GND1")
		(10 "In4.Cu" signal "IN2")
		(12 "In5.Cu" signal "GND2")
		(14 "In6.Cu" signal "IN3")
		(16 "In7.Cu" signal "GND3")
		(18 "In8.Cu" signal "VCC")
		(20 "In9.Cu" signal "VCC1")
		(22 "In10.Cu" signal "GND4")
		(24 "In11.Cu" signal "IN4")
		(26 "In12.Cu" signal "GND5")
		(28 "In13.Cu" signal "IN5")
		(30 "In14.Cu" signal "GND6")
		(32 "In15.Cu" signal "IN6")
		(34 "In16.Cu" signal "GND7")
		(2 "B.Cu" signal "BOTTOM")
		(9 "F.Adhes" user "F.Adhesive")
		(11 "B.Adhes" user "B.Adhesive")
		(13 "F.Paste" user "Package Geometry/Pastemask Top")
		(15 "B.Paste" user "Package Geometry/Pastemask Bottom")
		(5 "F.SilkS" user "Ref Des/Silkscreen Top")
		(7 "B.SilkS" user "Ref Des/Silkscreen Bottom")
		(1 "F.Mask" user "Board Geometry/Soldermask Top")
		(3 "B.Mask" user "Board Geometry/Soldermask Bottom")
		(17 "Dwgs.User" user "User.Drawings")
		(19 "Cmts.User" user "User.Comments")
		(21 "Eco1.User" user "User.Eco1")
		(23 "Eco2.User" user "User.Eco2")
		(25 "Edge.Cuts" user "Board Geometry/Outline")
		(27 "Margin" user)
		(31 "F.CrtYd" user "Package Geometry/Place Bound Top")
		(29 "B.CrtYd" user "Package Geometry/Place Bound Bottom")
		(35 "F.Fab" user "Ref Des/Assembly Top")
		(33 "B.Fab" user "Ref Des/Assembly Bottom")
	)
	(footprint ""
		(layer "B.Cu")
		(at 168.83888 -101.564948 180)
		(property "Reference" "R3346"
			(at 0 0 0)
			(layer "B.SilkS")
			(hide yes)
			(effects
				(font
					(size 1.27 1.27)
				)
				(justify mirror)
			)
		)
		(property "Value" ""
			(at 0 0 0)
			(layer "B.Fab")
			(effects
				(font
					(size 1.27 1.27)
				)
				(justify mirror)
			)
		)
		(duplicate_pad_numbers_are_jumpers no)
		(fp_line
			(start 1.2954 0.5842)
			(end 1.2954 -0.5842)
			(stroke
				(width 0.1524)
				(type default)
			)
			(layer "B.SilkS")
		)
		(fp_line
			(start 1.2954 -0.5842)
			(end -1.2954 -0.5842)
			(stroke
				(width 0.1524)
				(type default)
			)
			(layer "B.SilkS")
		)
		(fp_line
			(start -1.2954 0.5842)
			(end 1.2954 0.5842)
			(stroke
				(width 0.1524)
				(type default)
			)
			(layer "B.SilkS")
		)
		(fp_line
			(start -1.2954 -0.5842)
			(end -1.2954 0.5842)
			(stroke
				(width 0.1524)
				(type default)
			)
			(layer "B.SilkS")
		)
		(fp_line
			(start 1.1938 0.4064)
			(end 1.1938 -0.406654)
			(stroke
				(width 0.1)
				(type default)
			)
			(layer "B.Fab")
		)
		(fp_line
			(start 1.1938 -0.406654)
			(end 0.8636 -0.406654)
			(stroke
				(width 0.1)
				(type default)
			)
			(layer "B.Fab")
		)
		(fp_line
			(start 0.8636 0.4572)
			(end 0.8636 0.4318)
			(stroke
				(width 0.1)
				(type default)
			)
			(layer "B.Fab")
		)
		(fp_line
			(start 0.8636 0.4318)
			(end 0.8636 0.4064)
			(stroke
				(width 0.1)
				(type default)
			)
			(layer "B.Fab")
		)
		(fp_line
			(start 0.8636 0.4064)
			(end 1.1938 0.4064)
			(stroke
				(width 0.1)
				(type default)
			)
			(layer "B.Fab")
		)
		(fp_line
			(start 0.8636 -0.406654)
			(end 0.8636 -0.4572)
			(stroke
				(width 0.1)
				(type default)
			)
			(layer "B.Fab")
		)
		(fp_line
			(start 0.8636 -0.4572)
			(end -0.8636 -0.4572)
			(stroke
				(width 0.1)
				(type default)
			)
			(layer "B.Fab")
		)
		(fp_line
			(start -0.8636 0.4572)
			(end 0.8636 0.4572)
			(stroke
				(width 0.1)
				(type default)
			)
			(layer "B.Fab")
		)
		(fp_line
			(start -0.8636 0.4064)
			(end -0.8636 0.4572)
			(stroke
				(width 0.1)
				(type default)
			)
			(layer "B.Fab")
		)
		(fp_line
			(start -0.8636 -0.406654)
			(end -1.1938 -0.406654)
			(stroke
				(width 0.1)
				(type default)
			)
			(layer "B.Fab")
		)
		(fp_line
			(start -0.8636 -0.4572)
			(end -0.8636 -0.406654)
			(stroke
				(width 0.1)
				(type default)
			)
			(layer "B.Fab")
		)
		(fp_line
			(start -1.1938 0.4064)
			(end -0.8636 0.4064)
			(stroke
				(width 0.1)
				(type default)
			)
			(layer "B.Fab")
		)
		(fp_line
			(start -1.1938 -0.406654)
			(end -1.1938 0.4064)
			(stroke
				(width 0.1)
				(type default)
			)
			(layer "B.Fab")
		)
		(pad "1" smd rect
			(at 0.7366 0 90)
			(size 0.7112 0.8128)
			(layers "B.Cu" "B.Mask" "B.Paste")
			(net "P3V3_AUX")
		)
		(pad "2" smd rect
			(at -0.7366 0 90)
			(size 0.7112 0.8128)
			(layers "B.Cu" "B.Mask" "B.Paste")
			(net "P3V3_AUX_FPGA_VCCIO0")
		)
	)
	(footprint ""
		(layer "B.Cu")
		(at 366.098582 -210.19389)
		(property "Reference" "C530"
			(at 0 0 0)
			(layer "B.SilkS")
			(hide yes)
			(effects
				(font
					(size 1.27 1.27)
				)
				(justify mirror)
			)
		)
		(property "Value" ""
			(at 0 0 0)
			(layer "B.Fab")
			(effects
				(font
					(size 1.27 1.27)
				)
				(justify mirror)
			)
		)
		(duplicate_pad_numbers_are_jumpers no)
		(fp_line
			(start -1.524 -0.762)
			(end -1.524 0.762)
			(stroke
				(width 0.1524)
				(type default)
			)
			(layer "B.SilkS")
		)
		(fp_line
			(start -1.524 0.762)
			(end 1.524 0.762)
			(stroke
				(width 0.1524)
				(type default)
			)
			(layer "B.SilkS")
		)
		(fp_line
			(start 1.524 -0.762)
			(end -1.524 -0.762)
			(stroke
				(width 0.1524)
				(type default)
			)
			(layer "B.SilkS")
		)
		(fp_line
			(start 1.524 0.762)
			(end 1.524 -0.762)
			(stroke
				(width 0.1524)
				(type default)
			)
			(layer "B.SilkS")
		)
		(fp_line
			(start -1.1049 -0.724916)
			(end 1.1049 -0.724916)
			(stroke
				(width 0.1)
				(type default)
			)
			(layer "B.Fab")
		)
		(fp_line
			(start -1.1049 0.724916)
			(end -1.1049 -0.724916)
			(stroke
				(width 0.1)
				(type default)
			)
			(layer "B.Fab")
		)
		(fp_line
			(start 1.1049 -0.724916)
			(end 1.1049 0.724916)
			(stroke
				(width 0.1)
				(type default)
			)
			(layer "B.Fab")
		)
		(fp_line
			(start 1.1049 0.724916)
			(end -1.1049 0.724916)
			(stroke
				(width 0.1)
				(type default)
			)
			(layer "B.Fab")
		)
		(pad "1" smd rect
			(at 0.889 0)
			(size 1.016 1.27)
			(layers "B.Cu" "B.Mask" "B.Paste")
			(net "PVCCINFAON_CPU0")
		)
		(pad "2" smd rect
			(at -0.889 0)
			(size 1.016 1.27)
			(layers "B.Cu" "B.Mask" "B.Paste")
			(net "GND")
		)
	)
	(footprint ""
		(layer "B.Cu")
		(at 56.289702 -358.12349 180)
		(property "Reference" "PC1680"
			(at 0 0 0)
			(layer "B.SilkS")
			(hide yes)
			(effects
				(font
					(size 1.27 1.27)
				)
				(justify mirror)
			)
		)
		(property "Value" ""
			(at 0 0 0)
			(layer "B.Fab")
			(effects
				(font
					(size 1.27 1.27)
				)
				(justify mirror)
			)
		)
		(duplicate_pad_numbers_are_jumpers no)
		(fp_line
			(start 1.524 0.762)
			(end 1.524 -0.762)
			(stroke
				(width 0.1524)
				(type default)
			)
			(layer "B.SilkS")
		)
		(fp_line
			(start 1.524 -0.762)
			(end -1.524 -0.762)
			(stroke
				(width 0.1524)
				(type default)
			)
			(layer "B.SilkS")
		)
		(fp_line
			(start -1.524 0.762)
			(end 1.524 0.762)
			(stroke
				(width 0.1524)
				(type default)
			)
			(layer "B.SilkS")
		)
		(fp_line
			(start -1.524 -0.762)
			(end -1.524 0.762)
			(stroke
				(width 0.1524)
				(type default)
			)
			(layer "B.SilkS")
		)
		(fp_line
			(start 1.1049 0.724916)
			(end -1.1049 0.724916)
			(stroke
				(width 0.1)
				(type default)
			)
			(layer "B.Fab")
		)
		(fp_line
			(start 1.1049 -0.724916)
			(end 1.1049 0.724916)
			(stroke
				(width 0.1)
				(type default)
			)
			(layer "B.Fab")
		)
		(fp_line
			(start -1.1049 0.724916)
			(end -1.1049 -0.724916)
			(stroke
				(width 0.1)
				(type default)
			)
			(layer "B.Fab")
		)
		(fp_line
			(start -1.1049 -0.724916)
			(end 1.1049 -0.724916)
			(stroke
				(width 0.1)
				(type default)
			)
			(layer "B.Fab")
		)
		(pad "1" smd rect
			(at 0.889 0 180)
			(size 1.016 1.27)
			(layers "B.Cu" "B.Mask" "B.Paste")
			(net "SW_P12V_PVCCFA_EHV_FIVRA_CPU1_L")
		)
		(pad "2" smd rect
			(at -0.889 0 180)
			(size 1.016 1.27)
			(layers "B.Cu" "B.Mask" "B.Paste")
			(net "GND")
		)
	)
)
